(kicad_pcb
	(version 20260206)
	(generator "pcbnew")
	(generator_version "10.0")
	(general
		(thickness 1.6)
		(legacy_teardrops no)
	)
	(paper "A4")
	(title_block
		(title "Bryce Canyon_IOM_IOC_16318-2_OCP.brd")
		(comment 1 "Bryce Canyon / footprints 1179-1186 of 1605")
	)
	(layers
		(0 "F.Cu" signal "TOP")
		(4 "In1.Cu" signal "L2GND")
		(6 "In2.Cu" signal "L3")
		(8 "In3.Cu" signal "L4VCC")
		(10 "In4.Cu" signal "L5VCC")
		(12 "In5.Cu" signal "L6")
		(14 "In6.Cu" signal "L7GND")
		(2 "B.Cu" signal "BOTTOM")
		(9 "F.Adhes" user "F.Adhesive")
		(11 "B.Adhes" user "B.Adhesive")
		(13 "F.Paste" user "Package Geometry/Pastemask Top")
		(15 "B.Paste" user "Package Geometry/Pastemask Bottom")
		(5 "F.SilkS" user "Ref Des/Silkscreen Top")
		(7 "B.SilkS" user "Ref Des/Silkscreen Bottom")
		(1 "F.Mask" user "Board Geometry/Soldermask Top")
		(3 "B.Mask" user "Board Geometry/Soldermask Bottom")
		(17 "Dwgs.User" user "User.Drawings")
		(19 "Cmts.User" user "User.Comments")
		(21 "Eco1.User" user "User.Eco1")
		(23 "Eco2.User" user "User.Eco2")
		(25 "Edge.Cuts" user "Board Geometry/Outline")
		(27 "Margin" user)
		(31 "F.CrtYd" user "Package Geometry/Place Bound Top")
		(29 "B.CrtYd" user "Package Geometry/Place Bound Bottom")
		(35 "F.Fab" user "Ref Des/Assembly Top")
		(33 "B.Fab" user "Ref Des/Assembly Bottom")
	)
	(footprint ""
		(layer "B.Cu")
		(at 196.4182 -59.4106 90)
		(property "Reference" "C428"
			(at 0 0 90)
			(layer "B.SilkS")
			(hide yes)
			(effects
				(font
					(size 1.27 1.27)
				)
				(justify mirror)
			)
		)
		(property "Value" "SC1KP50V2KX-1GP"
			(at -1.1811 -2.7051 90)
			(unlocked yes)
			(layer "B.Fab")
			(hide yes)
			(effects
				(font
					(size 1.016 1.016)
					(thickness 0.1524)
				)
				(justify mirror)
			)
		)
		(property "Device Type" "C402H22"
			(at -1.1811 -4.2291 90)
			(unlocked yes)
			(layer "B.Fab")
			(hide yes)
			(effects
				(font
					(size 1.016 1.016)
					(thickness 0.1524)
				)
				(justify mirror)
			)
		)
		(duplicate_pad_numbers_are_jumpers no)
		(fp_rect
			(start 0.4318 0.9525)
			(end -0.4318 -0.9525)
			(stroke
				(width 0)
				(type default)
			)
			(fill no)
			(layer "B.CrtYd")
		)
		(fp_rect
			(start 0.4318 0.9525)
			(end -0.4318 -0.9525)
			(stroke
				(width 0)
				(type default)
			)
			(fill no)
			(layer "B.Fab")
		)
		(pad "1" smd custom
			(at 0 -0.4445 270)
			(size 0.1524 0.1524)
			(layers "B.Cu" "B.Mask" "B.Paste")
			(net "P0V975")
			(options
				(clearance outline)
				(anchor circle)
			)
			(primitives
				(gr_poly
					(pts
						(arc
							(start 0.3048 0.2032)
							(mid 0.275042 0.275042)
							(end 0.2032 0.3048)
						)
						(arc
							(start -0.2032 0.3048)
							(mid -0.275042 0.275042)
							(end -0.3048 0.2032)
						)
						(arc
							(start -0.3048 -0.2032)
							(mid -0.275042 -0.275042)
							(end -0.2032 -0.3048)
						)
						(arc
							(start 0.2032 -0.3048)
							(mid 0.275042 -0.275042)
							(end 0.3048 -0.2032)
						)
					)
					(width 0)
					(fill yes)
				)
			)
		)
		(pad "2" smd custom
			(at 0 0.4445 270)
			(size 0.1524 0.1524)
			(layers "B.Cu" "B.Mask" "B.Paste")
			(net "GND")
			(options
				(clearance outline)
				(anchor circle)
			)
			(primitives
				(gr_poly
					(pts
						(arc
							(start 0.3048 0.2032)
							(mid 0.275042 0.275042)
							(end 0.2032 0.3048)
						)
						(arc
							(start -0.2032 0.3048)
							(mid -0.275042 0.275042)
							(end -0.3048 0.2032)
						)
						(arc
							(start -0.3048 -0.2032)
							(mid -0.275042 -0.275042)
							(end -0.2032 -0.3048)
						)
						(arc
							(start 0.2032 -0.3048)
							(mid 0.275042 -0.275042)
							(end 0.3048 -0.2032)
						)
					)
					(width 0)
					(fill yes)
				)
			)
		)
	)
	(footprint ""
		(layer "B.Cu")
		(at 23.58898 -143.81861 180)
		(property "Reference" "C67"
			(at 0 0 0)
			(layer "B.SilkS")
			(hide yes)
			(effects
				(font
					(size 1.27 1.27)
				)
				(justify mirror)
			)
		)
		(property "Value" "SCD1U16V2KX-3GP"
			(at -1.1811 -2.7051 180)
			(unlocked yes)
			(layer "B.Fab")
			(hide yes)
			(effects
				(font
					(size 1.016 1.016)
					(thickness 0.1524)
				)
				(justify mirror)
			)
		)
		(property "Device Type" "C402H22"
			(at -1.1811 -4.2291 180)
			(unlocked yes)
			(layer "B.Fab")
			(hide yes)
			(effects
				(font
					(size 1.016 1.016)
					(thickness 0.1524)
				)
				(justify mirror)
			)
		)
		(duplicate_pad_numbers_are_jumpers no)
		(fp_rect
			(start 0.4318 0.9525)
			(end -0.4318 -0.9525)
			(stroke
				(width 0)
				(type default)
			)
			(fill no)
			(layer "B.CrtYd")
		)
		(fp_rect
			(start 0.4318 0.9525)
			(end -0.4318 -0.9525)
			(stroke
				(width 0)
				(type default)
			)
			(fill no)
			(layer "B.Fab")
		)
		(pad "1" smd custom
			(at 0 -0.4445)
			(size 0.1524 0.1524)
			(layers "B.Cu" "B.Mask" "B.Paste")
			(net "GND")
			(options
				(clearance outline)
				(anchor circle)
			)
			(primitives
				(gr_poly
					(pts
						(arc
							(start 0.3048 0.2032)
							(mid 0.275042 0.275042)
							(end 0.2032 0.3048)
						)
						(arc
							(start -0.2032 0.3048)
							(mid -0.275042 0.275042)
							(end -0.3048 0.2032)
						)
						(arc
							(start -0.3048 -0.2032)
							(mid -0.275042 -0.275042)
							(end -0.2032 -0.3048)
						)
						(arc
							(start 0.2032 -0.3048)
							(mid 0.275042 -0.275042)
							(end 0.3048 -0.2032)
						)
					)
					(width 0)
					(fill yes)
				)
			)
		)
		(pad "2" smd custom
			(at 0 0.4445)
			(size 0.1524 0.1524)
			(layers "B.Cu" "B.Mask" "B.Paste")
			(net "P1V2_STBY")
			(options
				(clearance outline)
				(anchor circle)
			)
			(primitives
				(gr_poly
					(pts
						(arc
							(start 0.3048 0.2032)
							(mid 0.275042 0.275042)
							(end 0.2032 0.3048)
						)
						(arc
							(start -0.2032 0.3048)
							(mid -0.275042 0.275042)
							(end -0.3048 0.2032)
						)
						(arc
							(start -0.3048 -0.2032)
							(mid -0.275042 -0.275042)
							(end -0.2032 -0.3048)
						)
						(arc
							(start 0.2032 -0.3048)
							(mid 0.275042 -0.275042)
							(end 0.3048 -0.2032)
						)
					)
					(width 0)
					(fill yes)
				)
			)
		)
	)
	(footprint ""
		(layer "B.Cu")
		(at 183.69534 -53.3019)
		(property "Reference" "TP167"
			(at 0 0 0)
			(layer "B.SilkS")
			(hide yes)
			(effects
				(font
					(size 1.27 1.27)
				)
				(justify mirror)
			)
		)
		(property "Value" "TPAD28-2-GP"
			(at 0.0127 -1.6637 0)
			(unlocked yes)
			(layer "B.Fab")
			(hide yes)
			(effects
				(font
					(size 1.016 1.016)
					(thickness 0.1524)
				)
				(justify mirror)
			)
		)
		(property "Device Type" "TPAD28"
			(at 0.0127 -3.1877 0)
			(unlocked yes)
			(layer "B.Fab")
			(hide yes)
			(effects
				(font
					(size 1.016 1.016)
					(thickness 0.1524)
				)
				(justify mirror)
			)
		)
		(duplicate_pad_numbers_are_jumpers no)
		(fp_poly
			(pts
				(arc
					(start 0.3556 0)
					(mid -0.3556 0)
					(end 0.3556 0)
				)
			)
			(stroke
				(width 0)
				(type default)
			)
			(fill no)
			(layer "B.CrtYd")
		)
		(fp_poly
			(pts
				(arc
					(start 0.6096 0)
					(mid -0.6096 0)
					(end 0.6096 0)
				)
			)
			(stroke
				(width 0)
				(type default)
			)
			(fill no)
			(layer "B.Fab")
		)
		(pad "1" smd circle
			(at 0 0 180)
			(size 0.7112 0.7112)
			(layers "B.Cu" "B.Mask" "B.Paste")
			(net "XM_WP")
		)
	)
	(footprint ""
		(layer "B.Cu")
		(at 39.723314 -150.106888)
		(property "Reference" "TP62"
			(at 0 0 0)
			(layer "B.SilkS")
			(hide yes)
			(effects
				(font
					(size 1.27 1.27)
				)
				(justify mirror)
			)
		)
		(property "Value" "TPAD28-2-GP"
			(at 0.0127 -1.6637 0)
			(unlocked yes)
			(layer "B.Fab")
			(hide yes)
			(effects
				(font
					(size 1.016 1.016)
					(thickness 0.1524)
				)
				(justify mirror)
			)
		)
		(property "Device Type" "TPAD28"
			(at 0.0127 -3.1877 0)
			(unlocked yes)
			(layer "B.Fab")
			(hide yes)
			(effects
				(font
					(size 1.016 1.016)
					(thickness 0.1524)
				)
				(justify mirror)
			)
		)
		(duplicate_pad_numbers_are_jumpers no)
		(fp_poly
			(pts
				(arc
					(start 0.3556 0)
					(mid -0.3556 0)
					(end 0.3556 0)
				)
			)
			(stroke
				(width 0)
				(type default)
			)
			(fill no)
			(layer "B.CrtYd")
		)
		(fp_poly
			(pts
				(arc
					(start 0.6096 0)
					(mid -0.6096 0)
					(end 0.6096 0)
				)
			)
			(stroke
				(width 0)
				(type default)
			)
			(fill no)
			(layer "B.Fab")
		)
		(pad "1" smd circle
			(at 0 0 180)
			(size 0.7112 0.7112)
			(layers "B.Cu" "B.Mask" "B.Paste")
			(net "TP_BMC_GPION2")
		)
	)
	(footprint ""
		(layer "B.Cu")
		(at 51.03114 -142.61846 180)
		(property "Reference" "R357"
			(at 0 0 0)
			(layer "B.SilkS")
			(hide yes)
			(effects
				(font
					(size 1.27 1.27)
				)
				(justify mirror)
			)
		)
		(property "Value" "4K7R2F-GP"
			(at -0.064008 -3.993896 180)
			(unlocked yes)
			(layer "B.Fab")
			(hide yes)
			(effects
				(font
					(size 1.016 1.016)
					(thickness 0.1524)
				)
				(justify mirror)
			)
		)
		(property "Device Type" "R402H16"
			(at -0.064008 -5.517896 180)
			(unlocked yes)
			(layer "B.Fab")
			(hide yes)
			(effects
				(font
					(size 1.016 1.016)
					(thickness 0.1524)
				)
				(justify mirror)
			)
		)
		(duplicate_pad_numbers_are_jumpers no)
		(fp_line
			(start 0.508 -0.9398)
			(end 0.508 0.9398)
			(stroke
				(width 0.1524)
				(type default)
			)
			(layer "B.SilkS")
		)
		(fp_line
			(start -0.508 -0.9398)
			(end 0.508 -0.9398)
			(stroke
				(width 0.1524)
				(type default)
			)
			(layer "B.SilkS")
		)
		(fp_rect
			(start 0.508 0.9398)
			(end -0.508 -0.9398)
			(stroke
				(width 0)
				(type default)
			)
			(fill no)
			(layer "B.CrtYd")
		)
		(fp_rect
			(start 0.508 0.9398)
			(end -0.508 -0.9398)
			(stroke
				(width 0)
				(type default)
			)
			(fill no)
			(layer "B.Fab")
		)
		(pad "1" smd custom
			(at 0 -0.4445)
			(size 0.1397 0.1397)
			(layers "B.Cu" "B.Mask" "B.Paste")
			(net "P3V3_STBY")
			(options
				(clearance outline)
				(anchor circle)
			)
			(primitives
				(gr_poly
					(pts
						(arc
							(start -0.1778 0.2794)
							(mid -0.249642 0.249642)
							(end -0.2794 0.1778)
						)
						(arc
							(start -0.2794 -0.1778)
							(mid -0.249642 -0.249642)
							(end -0.1778 -0.2794)
						)
						(arc
							(start 0.1778 -0.2794)
							(mid 0.249642 -0.249642)
							(end 0.2794 -0.1778)
						)
						(arc
							(start 0.2794 0.1778)
							(mid 0.249642 0.249642)
							(end 0.1778 0.2794)
						)
					)
					(width 0)
					(fill yes)
				)
			)
		)
		(pad "2" smd custom
			(at 0 0.4445)
			(size 0.1397 0.1397)
			(layers "B.Cu" "B.Mask" "B.Paste")
			(net "JTAG_BMC_TRST_N")
			(options
				(clearance outline)
				(anchor circle)
			)
			(primitives
				(gr_poly
					(pts
						(arc
							(start -0.1778 0.2794)
							(mid -0.249642 0.249642)
							(end -0.2794 0.1778)
						)
						(arc
							(start -0.2794 -0.1778)
							(mid -0.249642 -0.249642)
							(end -0.1778 -0.2794)
						)
						(arc
							(start 0.1778 -0.2794)
							(mid 0.249642 -0.249642)
							(end 0.2794 -0.1778)
						)
						(arc
							(start 0.2794 0.1778)
							(mid 0.249642 0.249642)
							(end 0.1778 0.2794)
						)
					)
					(width 0)
					(fill yes)
				)
			)
		)
	)
	(footprint ""
		(layer "B.Cu")
		(at 159.893 -48.895)
		(property "Reference" "R748"
			(at 0 0 0)
			(layer "B.SilkS")
			(hide yes)
			(effects
				(font
					(size 1.27 1.27)
				)
				(justify mirror)
			)
		)
		(property "Value" "10KR2F-2-GP"
			(at -0.064008 -3.993896 0)
			(unlocked yes)
			(layer "B.Fab")
			(hide yes)
			(effects
				(font
					(size 1.016 1.016)
					(thickness 0.1524)
				)
				(justify mirror)
			)
		)
		(property "Device Type" "R402H16"
			(at -0.064008 -5.517896 0)
			(unlocked yes)
			(layer "B.Fab")
			(hide yes)
			(effects
				(font
					(size 1.016 1.016)
					(thickness 0.1524)
				)
				(justify mirror)
			)
		)
		(duplicate_pad_numbers_are_jumpers no)
		(fp_line
			(start -0.508 -0.9398)
			(end 0.508 -0.9398)
			(stroke
				(width 0.1524)
				(type default)
			)
			(layer "B.SilkS")
		)
		(fp_line
			(start 0.508 -0.9398)
			(end 0.508 0.9398)
			(stroke
				(width 0.1524)
				(type default)
			)
			(layer "B.SilkS")
		)
		(fp_rect
			(start 0.508 0.9398)
			(end -0.508 -0.9398)
			(stroke
				(width 0)
				(type default)
			)
			(fill no)
			(layer "B.CrtYd")
		)
		(fp_rect
			(start 0.508 0.9398)
			(end -0.508 -0.9398)
			(stroke
				(width 0)
				(type default)
			)
			(fill no)
			(layer "B.Fab")
		)
		(pad "1" smd custom
			(at 0 -0.4445 180)
			(size 0.1397 0.1397)
			(layers "B.Cu" "B.Mask" "B.Paste")
			(net "BYTE_N")
			(options
				(clearance outline)
				(anchor circle)
			)
			(primitives
				(gr_poly
					(pts
						(arc
							(start -0.1778 0.2794)
							(mid -0.249642 0.249642)
							(end -0.2794 0.1778)
						)
						(arc
							(start -0.2794 -0.1778)
							(mid -0.249642 -0.249642)
							(end -0.1778 -0.2794)
						)
						(arc
							(start 0.1778 -0.2794)
							(mid 0.249642 -0.249642)
							(end 0.2794 -0.1778)
						)
						(arc
							(start 0.2794 0.1778)
							(mid 0.249642 0.249642)
							(end 0.1778 0.2794)
						)
					)
					(width 0)
					(fill yes)
				)
			)
		)
		(pad "2" smd custom
			(at 0 0.4445 180)
			(size 0.1397 0.1397)
			(layers "B.Cu" "B.Mask" "B.Paste")
			(net "GND")
			(options
				(clearance outline)
				(anchor circle)
			)
			(primitives
				(gr_poly
					(pts
						(arc
							(start -0.1778 0.2794)
							(mid -0.249642 0.249642)
							(end -0.2794 0.1778)
						)
						(arc
							(start -0.2794 -0.1778)
							(mid -0.249642 -0.249642)
							(end -0.1778 -0.2794)
						)
						(arc
							(start 0.1778 -0.2794)
							(mid 0.249642 -0.249642)
							(end 0.2794 -0.1778)
						)
						(arc
							(start 0.2794 0.1778)
							(mid 0.249642 0.249642)
							(end 0.1778 0.2794)
						)
					)
					(width 0)
					(fill yes)
				)
			)
		)
	)
	(footprint ""
		(layer "B.Cu")
		(at 190.8556 -63.7794 90)
		(property "Reference" "C413"
			(at 0 0 90)
			(layer "B.SilkS")
			(hide yes)
			(effects
				(font
					(size 1.27 1.27)
				)
				(justify mirror)
			)
		)
		(property "Value" "SCD1U6D3V1KX-GP"
			(at 2.8321 -1.7399 90)
			(unlocked yes)
			(layer "B.Fab")
			(hide yes)
			(effects
				(font
					(size 1.016 1.016)
					(thickness 0.1524)
				)
				(justify mirror)
			)
		)
		(property "Device Type" "C0201H13"
			(at 2.8321 -3.2639 90)
			(unlocked yes)
			(layer "B.Fab")
			(hide yes)
			(effects
				(font
					(size 1.016 1.016)
					(thickness 0.1524)
				)
				(justify mirror)
			)
		)
		(duplicate_pad_numbers_are_jumpers no)
		(fp_rect
			(start 0.2794 0.6477)
			(end -0.2794 -0.6477)
			(stroke
				(width 0)
				(type default)
			)
			(fill no)
			(layer "B.CrtYd")
		)
		(fp_rect
			(start 0.2794 0.6477)
			(end -0.2794 -0.6477)
			(stroke
				(width 0)
				(type default)
			)
			(fill no)
			(layer "B.Fab")
		)
		(pad "1" smd custom
			(at 0 -0.2794 270)
			(size 0.0762 0.0762)
			(layers "B.Cu" "B.Mask" "B.Paste")
			(net "P0V975")
			(options
				(clearance outline)
				(anchor circle)
			)
			(primitives
				(gr_poly
					(pts
						(arc
							(start 0.1524 0.127)
							(mid 0.137521 0.162921)
							(end 0.1016 0.1778)
						)
						(arc
							(start -0.1016 0.1778)
							(mid -0.137521 0.162921)
							(end -0.1524 0.127)
						)
						(arc
							(start -0.1524 -0.127)
							(mid -0.137521 -0.162921)
							(end -0.1016 -0.1778)
						)
						(arc
							(start 0.1016 -0.1778)
							(mid 0.137521 -0.162921)
							(end 0.1524 -0.127)
						)
					)
					(width 0)
					(fill yes)
				)
			)
		)
		(pad "2" smd custom
			(at 0 0.2794 270)
			(size 0.0762 0.0762)
			(layers "B.Cu" "B.Mask" "B.Paste")
			(net "GND")
			(options
				(clearance outline)
				(anchor circle)
			)
			(primitives
				(gr_poly
					(pts
						(arc
							(start 0.1524 0.127)
							(mid 0.137521 0.162921)
							(end 0.1016 0.1778)
						)
						(arc
							(start -0.1016 0.1778)
							(mid -0.137521 0.162921)
							(end -0.1524 0.127)
						)
						(arc
							(start -0.1524 -0.127)
							(mid -0.137521 -0.162921)
							(end -0.1016 -0.1778)
						)
						(arc
							(start 0.1016 -0.1778)
							(mid 0.137521 -0.162921)
							(end 0.1524 -0.127)
						)
					)
					(width 0)
					(fill yes)
				)
			)
		)
	)
	(footprint ""
		(layer "B.Cu")
		(at 43.483022 -161.366962 -90)
		(property "Reference" "R311"
			(at 0 0 90)
			(layer "B.SilkS")
			(hide yes)
			(effects
				(font
					(size 1.27 1.27)
				)
				(justify mirror)
			)
		)
		(property "Value" "4K7R2F-GP"
			(at -0.064008 -3.993896 270)
			(unlocked yes)
			(layer "B.Fab")
			(hide yes)
			(effects
				(font
					(size 1.016 1.016)
					(thickness 0.1524)
				)
				(justify mirror)
			)
		)
		(property "Device Type" "R402H16"
			(at -0.064008 -5.517896 270)
			(unlocked yes)
			(layer "B.Fab")
			(hide yes)
			(effects
				(font
					(size 1.016 1.016)
					(thickness 0.1524)
				)
				(justify mirror)
			)
		)
		(duplicate_pad_numbers_are_jumpers no)
		(fp_line
			(start -0.508 -0.9398)
			(end 0.508 -0.9398)
			(stroke
				(width 0.1524)
				(type default)
			)
			(layer "B.SilkS")
		)
		(fp_line
			(start 0.508 -0.9398)
			(end 0.508 0.9398)
			(stroke
				(width 0.1524)
				(type default)
			)
			(layer "B.SilkS")
		)
		(fp_rect
			(start 0.508 0.9398)
			(end -0.508 -0.9398)
			(stroke
				(width 0)
				(type default)
			)
			(fill no)
			(layer "B.CrtYd")
		)
		(fp_rect
			(start 0.508 0.9398)
			(end -0.508 -0.9398)
			(stroke
				(width 0)
				(type default)
			)
			(fill no)
			(layer "B.Fab")
		)
		(pad "1" smd custom
			(at 0 -0.4445 90)
			(size 0.1397 0.1397)
			(layers "B.Cu" "B.Mask" "B.Paste")
			(net "BOARD_REV_2")
			(options
				(clearance outline)
				(anchor circle)
			)
			(primitives
				(gr_poly
					(pts
						(arc
							(start -0.1778 0.2794)
							(mid -0.249642 0.249642)
							(end -0.2794 0.1778)
						)
						(arc
							(start -0.2794 -0.1778)
							(mid -0.249642 -0.249642)
							(end -0.1778 -0.2794)
						)
						(arc
							(start 0.1778 -0.2794)
							(mid 0.249642 -0.249642)
							(end 0.2794 -0.1778)
						)
						(arc
							(start 0.2794 0.1778)
							(mid 0.249642 0.249642)
							(end 0.1778 0.2794)
						)
					)
					(width 0)
					(fill yes)
				)
			)
		)
		(pad "2" smd custom
			(at 0 0.4445 90)
			(size 0.1397 0.1397)
			(layers "B.Cu" "B.Mask" "B.Paste")
			(net "P3V3_STBY")
			(options
				(clearance outline)
				(anchor circle)
			)
			(primitives
				(gr_poly
					(pts
						(arc
							(start -0.1778 0.2794)
							(mid -0.249642 0.249642)
							(end -0.2794 0.1778)
						)
						(arc
							(start -0.2794 -0.1778)
							(mid -0.249642 -0.249642)
							(end -0.1778 -0.2794)
						)
						(arc
							(start 0.1778 -0.2794)
							(mid 0.249642 -0.249642)
							(end 0.2794 -0.1778)
						)
						(arc
							(start 0.2794 0.1778)
							(mid 0.249642 0.249642)
							(end 0.1778 0.2794)
						)
					)
					(width 0)
					(fill yes)
				)
			)
		)
	)
)
